# T6G (Grand Teton) — schematic netlist excerpt (pin names and nets, part order shuffled) for the footprints in the layout excerpt that follows; sources: Cadence DE-HDL packaged netlist, KiCad conversion of 04192023_DAF0TMB3IC0_F0TG_MB_C_brd_V02_OCP.brd

R1092  Q_RES  10M 1% EMPTY  pkg 0402LF  page 169 : A = P3V3_AUX_DSC_G1 ; B = GND
R1776  Q_RES  1K 1% CHIP  pkg 0402LF  page 187 : A = CLR_CMOS ; B = GND

(kicad_pcb
	(version 20260206)
	(generator "pcbnew")
	(generator_version "10.0")
	(general
		(thickness 1.6)
		(legacy_teardrops no)
	)
	(paper "A4")
	(title_block
		(title "04192023_DAF0TMB3IC0_F0TG_MB_C_brd_V02_OCP.brd")
		(comment 1 "Grand Teton / footprints 1332-1333 of 8354")
	)
	(layers
		(0 "F.Cu" signal "TOP")
		(4 "In1.Cu" signal "GND")
		(6 "In2.Cu" signal "IN1")
		(8 "In3.Cu" signal "GND1")
		(10 "In4.Cu" signal "IN2")
		(12 "In5.Cu" signal "GND2")
		(14 "In6.Cu" signal "IN3")
		(16 "In7.Cu" signal "GND3")
		(18 "In8.Cu" signal "VCC")
		(20 "In9.Cu" signal "VCC1")
		(22 "In10.Cu" signal "GND4")
		(24 "In11.Cu" signal "IN4")
		(26 "In12.Cu" signal "GND5")
		(28 "In13.Cu" signal "IN5")
		(30 "In14.Cu" signal "GND6")
		(32 "In15.Cu" signal "IN6")
		(34 "In16.Cu" signal "GND7")
		(2 "B.Cu" signal "BOTTOM")
		(9 "F.Adhes" user "F.Adhesive")
		(11 "B.Adhes" user "B.Adhesive")
		(13 "F.Paste" user "Package Geometry/Pastemask Top")
		(15 "B.Paste" user "Package Geometry/Pastemask Bottom")
		(5 "F.SilkS" user "Ref Des/Silkscreen Top")
		(7 "B.SilkS" user "Ref Des/Silkscreen Bottom")
		(1 "F.Mask" user "Board Geometry/Soldermask Top")
		(3 "B.Mask" user "Board Geometry/Soldermask Bottom")
		(17 "Dwgs.User" user "User.Drawings")
		(19 "Cmts.User" user "User.Comments")
		(21 "Eco1.User" user "User.Eco1")
		(23 "Eco2.User" user "User.Eco2")
		(25 "Edge.Cuts" user "Board Geometry/Outline")
		(27 "Margin" user)
		(31 "F.CrtYd" user "Package Geometry/Place Bound Top")
		(29 "B.CrtYd" user "Package Geometry/Place Bound Bottom")
		(35 "F.Fab" user "Ref Des/Assembly Top")
		(33 "B.Fab" user "Ref Des/Assembly Bottom")
	)
	(footprint ""
		(layer "F.Cu")
		(at 44.7294 -105.8164 180)
		(property "Reference" "R1092"
			(at 0 0 180)
			(layer "F.SilkS")
			(hide yes)
			(effects
				(font
					(size 1.27 1.27)
				)
			)
		)
		(property "Value" ""
			(at 0 0 180)
			(layer "F.Fab")
			(effects
				(font
					(size 1.27 1.27)
				)
			)
		)
		(duplicate_pad_numbers_are_jumpers no)
		(fp_line
			(start 0.7874 0.4064)
			(end -0.7874 0.4064)
			(stroke
				(width 0.1524)
				(type default)
			)
			(layer "F.SilkS")
		)
		(fp_line
			(start 0.7874 -0.4064)
			(end 0.7874 0.4064)
			(stroke
				(width 0.1524)
				(type default)
			)
			(layer "F.SilkS")
		)
		(fp_line
			(start -0.7874 0.4064)
			(end -0.7874 -0.4064)
			(stroke
				(width 0.1524)
				(type default)
			)
			(layer "F.SilkS")
		)
		(fp_line
			(start -0.7874 -0.4064)
			(end 0.7874 -0.4064)
			(stroke
				(width 0.1524)
				(type default)
			)
			(layer "F.SilkS")
		)
		(fp_line
			(start 0.67945 0.3048)
			(end 0.120396 0.3048)
			(stroke
				(width 0.1)
				(type default)
			)
			(layer "F.Fab")
		)
		(fp_line
			(start 0.67945 -0.3048)
			(end 0.67945 0.3048)
			(stroke
				(width 0.1)
				(type default)
			)
			(layer "F.Fab")
		)
		(fp_line
			(start 0.12065 -0.2794)
			(end 0.12065 -0.3048)
			(stroke
				(width 0.1)
				(type default)
			)
			(layer "F.Fab")
		)
		(fp_line
			(start 0.12065 -0.3048)
			(end 0.67945 -0.3048)
			(stroke
				(width 0.1)
				(type default)
			)
			(layer "F.Fab")
		)
		(fp_line
			(start 0.120396 0.3048)
			(end 0.120396 0.2794)
			(stroke
				(width 0.1)
				(type default)
			)
			(layer "F.Fab")
		)
		(fp_line
			(start 0.120396 0.2794)
			(end -0.12065 0.2794)
			(stroke
				(width 0.1)
				(type default)
			)
			(layer "F.Fab")
		)
		(fp_line
			(start -0.12065 0.3048)
			(end -0.67945 0.3048)
			(stroke
				(width 0.1)
				(type default)
			)
			(layer "F.Fab")
		)
		(fp_line
			(start -0.12065 0.2794)
			(end -0.12065 0.3048)
			(stroke
				(width 0.1)
				(type default)
			)
			(layer "F.Fab")
		)
		(fp_line
			(start -0.12065 -0.2794)
			(end 0.12065 -0.2794)
			(stroke
				(width 0.1)
				(type default)
			)
			(layer "F.Fab")
		)
		(fp_line
			(start -0.12065 -0.305054)
			(end -0.12065 -0.2794)
			(stroke
				(width 0.1)
				(type default)
			)
			(layer "F.Fab")
		)
		(fp_line
			(start -0.67945 0.3048)
			(end -0.67945 -0.305054)
			(stroke
				(width 0.1)
				(type default)
			)
			(layer "F.Fab")
		)
		(fp_line
			(start -0.67945 -0.305054)
			(end -0.12065 -0.305054)
			(stroke
				(width 0.1)
				(type default)
			)
			(layer "F.Fab")
		)
		(pad "1" smd circle
			(at -0.40005 0 180)
			(size 0 0)
			(layers "F.Cu" "F.Mask" "F.Paste")
			(net "P3V3_AUX_DSC_G1")
		)
		(pad "2" smd circle
			(at 0.40005 0 180)
			(size 0 0)
			(layers "F.Cu" "F.Mask" "F.Paste")
			(net "GND")
		)
	)
	(footprint ""
		(layer "F.Cu")
		(at 301.621952 -23.14575)
		(property "Reference" "R1776"
			(at 0 0 0)
			(layer "F.SilkS")
			(hide yes)
			(effects
				(font
					(size 1.27 1.27)
				)
			)
		)
		(property "Value" ""
			(at 0 0 0)
			(layer "F.Fab")
			(effects
				(font
					(size 1.27 1.27)
				)
			)
		)
		(duplicate_pad_numbers_are_jumpers no)
		(fp_line
			(start -0.7874 -0.4064)
			(end 0.7874 -0.4064)
			(stroke
				(width 0.1524)
				(type default)
			)
			(layer "F.SilkS")
		)
		(fp_line
			(start -0.7874 0.4064)
			(end -0.7874 -0.4064)
			(stroke
				(width 0.1524)
				(type default)
			)
			(layer "F.SilkS")
		)
		(fp_line
			(start 0.7874 -0.4064)
			(end 0.7874 0.4064)
			(stroke
				(width 0.1524)
				(type default)
			)
			(layer "F.SilkS")
		)
		(fp_line
			(start 0.7874 0.4064)
			(end -0.7874 0.4064)
			(stroke
				(width 0.1524)
				(type default)
			)
			(layer "F.SilkS")
		)
		(fp_line
			(start -0.67945 -0.305054)
			(end -0.12065 -0.305054)
			(stroke
				(width 0.1)
				(type default)
			)
			(layer "F.Fab")
		)
		(fp_line
			(start -0.67945 0.3048)
			(end -0.67945 -0.305054)
			(stroke
				(width 0.1)
				(type default)
			)
			(layer "F.Fab")
		)
		(fp_line
			(start -0.12065 -0.305054)
			(end -0.12065 -0.2794)
			(stroke
				(width 0.1)
				(type default)
			)
			(layer "F.Fab")
		)
		(fp_line
			(start -0.12065 -0.2794)
			(end 0.12065 -0.2794)
			(stroke
				(width 0.1)
				(type default)
			)
			(layer "F.Fab")
		)
		(fp_line
			(start -0.12065 0.2794)
			(end -0.12065 0.3048)
			(stroke
				(width 0.1)
				(type default)
			)
			(layer "F.Fab")
		)
		(fp_line
			(start -0.12065 0.3048)
			(end -0.67945 0.3048)
			(stroke
				(width 0.1)
				(type default)
			)
			(layer "F.Fab")
		)
		(fp_line
			(start 0.120396 0.2794)
			(end -0.12065 0.2794)
			(stroke
				(width 0.1)
				(type default)
			)
			(layer "F.Fab")
		)
		(fp_line
			(start 0.120396 0.3048)
			(end 0.120396 0.2794)
			(stroke
				(width 0.1)
				(type default)
			)
			(layer "F.Fab")
		)
		(fp_line
			(start 0.12065 -0.3048)
			(end 0.67945 -0.3048)
			(stroke
				(width 0.1)
				(type default)
			)
			(layer "F.Fab")
		)
		(fp_line
			(start 0.12065 -0.2794)
			(end 0.12065 -0.3048)
			(stroke
				(width 0.1)
				(type default)
			)
			(layer "F.Fab")
		)
		(fp_line
			(start 0.67945 -0.3048)
			(end 0.67945 0.3048)
			(stroke
				(width 0.1)
				(type default)
			)
			(layer "F.Fab")
		)
		(fp_line
			(start 0.67945 0.3048)
			(end 0.120396 0.3048)
			(stroke
				(width 0.1)
				(type default)
			)
			(layer "F.Fab")
		)
		(pad "1" smd circle
			(at -0.40005 0)
			(size 0 0)
			(layers "F.Cu" "F.Mask" "F.Paste")
			(net "CLR_CMOS")
		)
		(pad "2" smd circle
			(at 0.40005 0)
			(size 0 0)
			(layers "F.Cu" "F.Mask" "F.Paste")
			(net "GND")
		)
	)
)
